# S9S_MB_2U (Grand Teton) — schematic netlist excerpt (pin names and nets, part order shuffled) for the footprints in the layout excerpt that follows; sources: Cadence DE-HDL packaged netlist, KiCad conversion of 03242023_DA0F0TMBIJ0_F0T_Motherboard_J_brd_V01_OCP.brd

R3068  Q_RES  130 1% CHIP  pkg 0402LF  page 255 : A = LED_PWRGD_PCH_PWROK_R ; B = P3V3_AUX
C1991  Q_CAP_DIFFBUS  DIFF BUS_0.22UF 6.3V 20% X6S  pkg C0201  page 181 : \1\ = P3E_PCH_E1S_TX_DP<2> ; \2\ = P3E_PCH_E1S_TX_C_DP<2>

(kicad_pcb
	(version 20260206)
	(generator "pcbnew")
	(generator_version "10.0")
	(general
		(thickness 1.6)
		(legacy_teardrops no)
	)
	(paper "A4")
	(title_block
		(title "03242023_DA0F0TMBIJ0_F0T_Motherboard_J_brd_V01_OCP.brd")
		(comment 1 "Grand Teton / footprints 1509-1510 of 6105")
	)
	(layers
		(0 "F.Cu" signal "TOP")
		(4 "In1.Cu" signal "GND")
		(6 "In2.Cu" signal "IN1")
		(8 "In3.Cu" signal "GND1")
		(10 "In4.Cu" signal "IN2")
		(12 "In5.Cu" signal "GND2")
		(14 "In6.Cu" signal "IN3")
		(16 "In7.Cu" signal "GND3")
		(18 "In8.Cu" signal "VCC")
		(20 "In9.Cu" signal "VCC1")
		(22 "In10.Cu" signal "GND4")
		(24 "In11.Cu" signal "IN4")
		(26 "In12.Cu" signal "GND5")
		(28 "In13.Cu" signal "IN5")
		(30 "In14.Cu" signal "GND6")
		(32 "In15.Cu" signal "IN6")
		(34 "In16.Cu" signal "GND7")
		(2 "B.Cu" signal "BOTTOM")
		(9 "F.Adhes" user "F.Adhesive")
		(11 "B.Adhes" user "B.Adhesive")
		(13 "F.Paste" user "Package Geometry/Pastemask Top")
		(15 "B.Paste" user "Package Geometry/Pastemask Bottom")
		(5 "F.SilkS" user "Ref Des/Silkscreen Top")
		(7 "B.SilkS" user "Ref Des/Silkscreen Bottom")
		(1 "F.Mask" user "Board Geometry/Soldermask Top")
		(3 "B.Mask" user "Board Geometry/Soldermask Bottom")
		(17 "Dwgs.User" user "User.Drawings")
		(19 "Cmts.User" user "User.Comments")
		(21 "Eco1.User" user "User.Eco1")
		(23 "Eco2.User" user "User.Eco2")
		(25 "Edge.Cuts" user "Board Geometry/Outline")
		(27 "Margin" user)
		(31 "F.CrtYd" user "Package Geometry/Place Bound Top")
		(29 "B.CrtYd" user "Package Geometry/Place Bound Bottom")
		(35 "F.Fab" user "Ref Des/Assembly Top")
		(33 "B.Fab" user "Ref Des/Assembly Bottom")
	)
	(footprint ""
		(layer "F.Cu")
		(at 240.854484 -56.527192 180)
		(property "Reference" "C1991"
			(at 0 0 180)
			(layer "F.SilkS")
			(hide yes)
			(effects
				(font
					(size 1.27 1.27)
				)
			)
		)
		(property "Value" ""
			(at 0 0 180)
			(layer "F.Fab")
			(effects
				(font
					(size 1.27 1.27)
				)
			)
		)
		(duplicate_pad_numbers_are_jumpers no)
		(fp_line
			(start 0.299974 0.150114)
			(end -0.299974 0.150114)
			(stroke
				(width 0.1)
				(type default)
			)
			(layer "F.Fab")
		)
		(fp_line
			(start 0.299974 -0.150114)
			(end 0.299974 0.150114)
			(stroke
				(width 0.1)
				(type default)
			)
			(layer "F.Fab")
		)
		(fp_line
			(start -0.299974 0.150114)
			(end -0.299974 -0.150114)
			(stroke
				(width 0.1)
				(type default)
			)
			(layer "F.Fab")
		)
		(fp_line
			(start -0.299974 -0.150114)
			(end 0.299974 -0.150114)
			(stroke
				(width 0.1)
				(type default)
			)
			(layer "F.Fab")
		)
		(pad "1" smd rect
			(at -0.2667 0 180)
			(size 0.3048 0.381)
			(layers "F.Cu" "F.Mask" "F.Paste")
			(net "P3E_PCH_E1S_TX_DP<2>")
		)
		(pad "2" smd rect
			(at 0.2667 0 180)
			(size 0.3048 0.381)
			(layers "F.Cu" "F.Mask" "F.Paste")
			(net "P3E_PCH_E1S_TX_C_DP<2>")
		)
		(zone
			(layer "In1.Cu")
			(hatch none 0.5)
			(connect_pads
				(clearance 0)
			)
			(min_thickness 0.25)
			(keepout
				(tracks not_allowed)
				(vias allowed)
				(pads allowed)
				(copperpour not_allowed)
				(footprints allowed)
			)
			(placement
				(enabled no)
				(sheetname "")
			)
			(fill
				(thermal_gap 0.5)
				(thermal_bridge_width 0.5)
				(island_removal_mode 0)
			)
			(polygon
				(pts
					(arc
						(start 240.714784 -56.767476)
						(mid 240.768666 -56.745158)
						(end 240.790984 -56.691276)
					)
					(arc
						(start 240.790984 -56.361076)
						(mid 240.768666 -56.307194)
						(end 240.714784 -56.284876)
					)
					(arc
						(start 240.460784 -56.284876)
						(mid 240.406902 -56.307194)
						(end 240.384584 -56.361076)
					)
					(arc
						(start 240.384584 -56.691276)
						(mid 240.406902 -56.745158)
						(end 240.460784 -56.767476)
					)
				)
			)
		)
		(zone
			(layer "In1.Cu")
			(hatch none 0.5)
			(connect_pads
				(clearance 0)
			)
			(min_thickness 0.25)
			(keepout
				(tracks not_allowed)
				(vias allowed)
				(pads allowed)
				(copperpour not_allowed)
				(footprints allowed)
			)
			(placement
				(enabled no)
				(sheetname "")
			)
			(fill
				(thermal_gap 0.5)
				(thermal_bridge_width 0.5)
				(island_removal_mode 0)
			)
			(polygon
				(pts
					(arc
						(start 241.248184 -56.767476)
						(mid 241.302066 -56.745158)
						(end 241.324384 -56.691276)
					)
					(arc
						(start 241.324384 -56.361076)
						(mid 241.302066 -56.307194)
						(end 241.248184 -56.284876)
					)
					(arc
						(start 240.994184 -56.284876)
						(mid 240.940302 -56.307194)
						(end 240.917984 -56.361076)
					)
					(arc
						(start 240.917984 -56.691276)
						(mid 240.940302 -56.745158)
						(end 240.994184 -56.767476)
					)
				)
			)
		)
	)
	(footprint ""
		(layer "F.Cu")
		(at 93.295724 -65.223644 -90)
		(property "Reference" "R3068"
			(at 0 0 270)
			(layer "F.SilkS")
			(hide yes)
			(effects
				(font
					(size 1.27 1.27)
				)
			)
		)
		(property "Value" ""
			(at 0 0 270)
			(layer "F.Fab")
			(effects
				(font
					(size 1.27 1.27)
				)
			)
		)
		(duplicate_pad_numbers_are_jumpers no)
		(fp_line
			(start -0.7874 0.4064)
			(end -0.7874 -0.4064)
			(stroke
				(width 0.1524)
				(type default)
			)
			(layer "F.SilkS")
		)
		(fp_line
			(start 0.7874 0.4064)
			(end -0.7874 0.4064)
			(stroke
				(width 0.1524)
				(type default)
			)
			(layer "F.SilkS")
		)
		(fp_line
			(start -0.7874 -0.4064)
			(end 0.7874 -0.4064)
			(stroke
				(width 0.1524)
				(type default)
			)
			(layer "F.SilkS")
		)
		(fp_line
			(start 0.7874 -0.4064)
			(end 0.7874 0.4064)
			(stroke
				(width 0.1524)
				(type default)
			)
			(layer "F.SilkS")
		)
		(fp_line
			(start -0.67945 0.3048)
			(end -0.67945 -0.305054)
			(stroke
				(width 0.1)
				(type default)
			)
			(layer "F.Fab")
		)
		(fp_line
			(start -0.12065 0.3048)
			(end -0.67945 0.3048)
			(stroke
				(width 0.1)
				(type default)
			)
			(layer "F.Fab")
		)
		(fp_line
			(start 0.120396 0.3048)
			(end 0.120396 0.2794)
			(stroke
				(width 0.1)
				(type default)
			)
			(layer "F.Fab")
		)
		(fp_line
			(start 0.67945 0.3048)
			(end 0.120396 0.3048)
			(stroke
				(width 0.1)
				(type default)
			)
			(layer "F.Fab")
		)
		(fp_line
			(start -0.12065 0.2794)
			(end -0.12065 0.3048)
			(stroke
				(width 0.1)
				(type default)
			)
			(layer "F.Fab")
		)
		(fp_line
			(start 0.120396 0.2794)
			(end -0.12065 0.2794)
			(stroke
				(width 0.1)
				(type default)
			)
			(layer "F.Fab")
		)
		(fp_line
			(start -0.12065 -0.2794)
			(end 0.12065 -0.2794)
			(stroke
				(width 0.1)
				(type default)
			)
			(layer "F.Fab")
		)
		(fp_line
			(start 0.12065 -0.2794)
			(end 0.12065 -0.3048)
			(stroke
				(width 0.1)
				(type default)
			)
			(layer "F.Fab")
		)
		(fp_line
			(start 0.12065 -0.3048)
			(end 0.67945 -0.3048)
			(stroke
				(width 0.1)
				(type default)
			)
			(layer "F.Fab")
		)
		(fp_line
			(start 0.67945 -0.3048)
			(end 0.67945 0.3048)
			(stroke
				(width 0.1)
				(type default)
			)
			(layer "F.Fab")
		)
		(fp_line
			(start -0.67945 -0.305054)
			(end -0.12065 -0.305054)
			(stroke
				(width 0.1)
				(type default)
			)
			(layer "F.Fab")
		)
		(fp_line
			(start -0.12065 -0.305054)
			(end -0.12065 -0.2794)
			(stroke
				(width 0.1)
				(type default)
			)
			(layer "F.Fab")
		)
		(pad "1" smd circle
			(at -0.40005 0 270)
			(size 0 0)
			(layers "F.Cu" "F.Mask" "F.Paste")
			(net "LED_PWRGD_PCH_PWROK_R")
		)
		(pad "2" smd circle
			(at 0.40005 0 270)
			(size 0 0)
			(layers "F.Cu" "F.Mask" "F.Paste")
			(net "P3V3_AUX")
		)
	)
)
